# BASEBOARD_FAB2 (Tioga Pass) — schematic netlist excerpt (pin names and nets, part order shuffled) for the footprints in the layout excerpt that follows; sources: Cadence DE-HDL packaged netlist, KiCad conversion of Wiwynn_Tioga_Pass_MB.brd

J9B3  SCONN120_A28699018  SCONN  pkg SM  page 186
  IO1  = FM_MEZZA_PRSNT1_N
  IO2  = P12V_STBY
  IO3  = P5V_STBY
  IO4  = P12V_STBY
  IO5  = P5V_STBY
  IO6  = P12V_STBY
  IO7  = P5V_STBY
  IO8  = GND
  IO9  = GND
  IO10  = GND
  IO11  = GND
  IO12  = P3V3_STBY
  IO13  = P3V3_STBY
  IO14  = GND
  IO15  = GND
  IO16  = GND
  IO17  = GND
  IO18  = P3V3
  IO19  = P3V3
  IO20  = P3V3
  IO21  = P3V3
  IO22  = P3V3
  IO23  = P3V3
  IO24  = P3V3
  IO25  = P3V3
  IO26  = GND
  IO27  = RMII_BMC_OCP_CRSDV_R
  IO28  = IRQ_MEZZ_LAN_ALERT_N
  IO29  = CLK_50M_CKMNG_OCP
  IO30  = SMB_OCP_FRU_STBY_LVC3_SCL
  IO31  = RMII_BMC_OCP_TXEN
  IO32  = SMB_OCP_FRU_STBY_LVC3_SDA
  IO33  = RST_PCIE_CPU_DEV0_R_N
  IO34  = FM_PE_OCP_WAKE_N
  IO35  = SMB_OCP_LAN_STBY_LVC3_SCL
  IO36  = RMII_BMC_OCP_RXER_R
  IO37  = SMB_OCP_LAN_STBY_LVC3_SDA
  IO38  = GND
  IO39  = GND
  IO40  = RMII_BMC_OCP_TXD0
  IO41  = GND
  IO42  = RMII_BMC_OCP_TXD1
  IO43  = RMII_BMC_OCP_RXD0_R
  IO44  = GND
  IO45  = RMII_BMC_OCP_RXD1_R
  IO46  = GND
  IO47  = GND
  IO48  = CLK_100M_MEZZ1_DP
  IO49  = GND
  IO50  = CLK_100M_MEZZ1_DN
  IO51  = CLK_100M_MEZZ2_DP
  IO52  = GND
  IO53  = CLK_100M_MEZZ2_DN
  IO54  = GND
  IO55  = GND
  IO56  = P3E_OCP_CPU0_PE3_C_TXP<15>
  IO57  = GND
  IO58  = P3E_OCP_CPU0_PE3_C_TXN<15>
  IO59  = P3E_CPU0_PE3_OCP_RXP<15>
  IO60  = GND
  IO61  = P3E_CPU0_PE3_OCP_RXN<15>
  IO62  = GND
  IO63  = GND
  IO64  = P3E_OCP_CPU0_PE3_C_TXP<14>
  IO65  = GND
  IO66  = P3E_OCP_CPU0_PE3_C_TXN<14>
  IO67  = P3E_CPU0_PE3_OCP_RXP<14>
  IO68  = GND
  IO69  = P3E_CPU0_PE3_OCP_RXN<14>
  IO70  = GND
  IO71  = GND
  IO72  = P3E_OCP_CPU0_PE3_C_TXP<13>
  IO73  = GND
  IO74  = P3E_OCP_CPU0_PE3_C_TXN<13>
  IO75  = P3E_CPU0_PE3_OCP_RXP<13>
  IO76  = GND
  IO77  = P3E_CPU0_PE3_OCP_RXN<13>
  IO78  = GND
  IO79  = GND
  IO80  = P3E_OCP_CPU0_PE3_C_TXP<12>
  IO81  = GND
  IO82  = P3E_OCP_CPU0_PE3_C_TXN<12>
  IO83  = P3E_CPU0_PE3_OCP_RXP<12>
  IO84  = GND
  IO85  = P3E_CPU0_PE3_OCP_RXN<12>
  IO86  = GND
  IO87  = GND
  IO88  = P3E_OCP_CPU0_PE3_C_TXP<11>
  IO89  = GND
  IO90  = P3E_OCP_CPU0_PE3_C_TXN<11>
  IO91  = P3E_CPU0_PE3_OCP_RXP<11>
  IO92  = GND
  IO93  = P3E_CPU0_PE3_OCP_RXN<11>
  IO94  = GND
  IO95  = GND
  IO96  = P3E_OCP_CPU0_PE3_C_TXP<10>
  IO97  = GND
  IO98  = P3E_OCP_CPU0_PE3_C_TXN<10>
  IO99  = P3E_CPU0_PE3_OCP_RXP<10>
  IO100  = GND
  IO101  = P3E_CPU0_PE3_OCP_RXN<10>
  IO102  = GND
  IO103  = GND
  IO104  = P3E_OCP_CPU0_PE3_C_TXP<9>
  IO105  = GND
  IO106  = P3E_OCP_CPU0_PE3_C_TXN<9>
  IO107  = P3E_CPU0_PE3_OCP_RXP<9>
  IO108  = GND
  IO109  = P3E_CPU0_PE3_OCP_RXN<9>
  IO110  = GND
  IO111  = GND
  IO112  = P3E_OCP_CPU0_PE3_C_TXP<8>
  IO113  = GND
  IO114  = P3E_OCP_CPU0_PE3_C_TXN<8>
  IO115  = P3E_CPU0_PE3_OCP_RXP<8>
  IO116  = GND
  IO117  = P3E_CPU0_PE3_OCP_RXN<8>
  IO118  = GND
  IO119  = GND
  IO120  = FM_OCP_MEZZA_PRES_N

(kicad_pcb
	(version 20260206)
	(generator "pcbnew")
	(generator_version "10.0")
	(general
		(thickness 1.6)
		(legacy_teardrops no)
	)
	(paper "A4")
	(title_block
		(title "Wiwynn_Tioga_Pass_MB.brd")
		(comment 1 "Tioga Pass / footprint 368 of 4770 (J9B3), pads 1-49 of 122")
	)
	(layers
		(0 "F.Cu" signal "TOP")
		(4 "In1.Cu" signal "L2GND")
		(6 "In2.Cu" signal "L3")
		(8 "In3.Cu" signal "L4GND")
		(10 "In4.Cu" signal "L5")
		(12 "In5.Cu" signal "L6GND")
		(14 "In6.Cu" signal "L7VCC")
		(16 "In7.Cu" signal "L8VCC")
		(18 "In8.Cu" signal "L9GND")
		(20 "In9.Cu" signal "L10")
		(22 "In10.Cu" signal "L11GND")
		(24 "In11.Cu" signal "L12")
		(26 "In12.Cu" signal "L13GND")
		(2 "B.Cu" signal "BOTTOM")
		(9 "F.Adhes" user "F.Adhesive")
		(11 "B.Adhes" user "B.Adhesive")
		(13 "F.Paste" user "Package Geometry/Pastemask Top")
		(15 "B.Paste" user "Package Geometry/Pastemask Bottom")
		(5 "F.SilkS" user "Ref Des/Silkscreen Top")
		(7 "B.SilkS" user "Ref Des/Silkscreen Bottom")
		(1 "F.Mask" user "Board Geometry/Soldermask Top")
		(3 "B.Mask" user "Board Geometry/Soldermask Bottom")
		(17 "Dwgs.User" user "User.Drawings")
		(19 "Cmts.User" user "User.Comments")
		(21 "Eco1.User" user "User.Eco1")
		(23 "Eco2.User" user "User.Eco2")
		(25 "Edge.Cuts" user "Board Geometry/Outline")
		(27 "Margin" user)
		(31 "F.CrtYd" user "Package Geometry/Place Bound Top")
		(29 "B.CrtYd" user "Package Geometry/Place Bound Bottom")
		(35 "F.Fab" user "Ref Des/Assembly Top")
		(33 "B.Fab" user "Ref Des/Assembly Bottom")
	)
	(footprint ""
		(layer "F.Cu")
		(at 487.800904 -116.993162 -90)
		(property "Reference" "J9B3"
			(at -2.227072 26.281888 0)
			(unlocked yes)
			(layer "F.SilkS")
			(effects
				(font
					(size 0.7874 0.5842)
					(thickness 0.1524)
				)
			)
		)
		(property "Value" ""
			(at 0 0 270)
			(layer "F.Fab")
			(effects
				(font
					(size 1.27 1.27)
				)
			)
		)
		(duplicate_pad_numbers_are_jumpers no)
		(pad "" np_thru_hole circle
			(at 2.393696 -2.500122 270)
			(size 0.254 0.254)
			(drill 1.1938)
			(layers "*.Cu" "*.Mask")
			(clearance 0.7874)
			(thermal_gap 0.7874)
		)
		(pad "" np_thru_hole circle
			(at 2.393696 49.699926 270)
			(size 0.254 0.254)
			(drill 0.8128)
			(layers "*.Cu" "*.Mask")
			(clearance 0.5969)
			(thermal_gap 0.5969)
		)
		(pad "1" smd rect
			(at 0 0 270)
			(size 2.3876 0.508)
			(layers "F.Cu" "F.Mask" "F.Paste")
			(net "FM_MEZZA_PRSNT1_N")
		)
		(pad "2" smd rect
			(at 4.787646 0 270)
			(size 2.3876 0.508)
			(layers "F.Cu" "F.Mask" "F.Paste")
			(net "P12V_STBY")
		)
		(pad "3" smd rect
			(at 0 0.8001 270)
			(size 2.3876 0.508)
			(layers "F.Cu" "F.Mask" "F.Paste")
			(net "P5V_STBY")
		)
		(pad "4" smd rect
			(at 4.787646 0.8001 270)
			(size 2.3876 0.508)
			(layers "F.Cu" "F.Mask" "F.Paste")
			(net "P12V_STBY")
		)
		(pad "5" smd rect
			(at 0 1.599946 270)
			(size 2.3876 0.508)
			(layers "F.Cu" "F.Mask" "F.Paste")
			(net "P5V_STBY")
		)
		(pad "6" smd rect
			(at 4.787646 1.599946 270)
			(size 2.3876 0.508)
			(layers "F.Cu" "F.Mask" "F.Paste")
			(net "P12V_STBY")
		)
		(pad "7" smd rect
			(at 0 2.400046 270)
			(size 2.3876 0.508)
			(layers "F.Cu" "F.Mask" "F.Paste")
			(net "P5V_STBY")
		)
		(pad "8" smd rect
			(at 4.787646 2.400046 270)
			(size 2.3876 0.508)
			(layers "F.Cu" "F.Mask" "F.Paste")
			(net "GND")
		)
		(pad "9" smd rect
			(at 0 3.199892 270)
			(size 2.3876 0.508)
			(layers "F.Cu" "F.Mask" "F.Paste")
			(net "GND")
		)
		(pad "10" smd rect
			(at 4.787646 3.199892 270)
			(size 2.3876 0.508)
			(layers "F.Cu" "F.Mask" "F.Paste")
			(net "GND")
		)
		(pad "11" smd rect
			(at 0 3.999992 270)
			(size 2.3876 0.508)
			(layers "F.Cu" "F.Mask" "F.Paste")
			(net "GND")
		)
		(pad "12" smd rect
			(at 4.787646 3.999992 270)
			(size 2.3876 0.508)
			(layers "F.Cu" "F.Mask" "F.Paste")
			(net "P3V3_STBY")
		)
		(pad "13" smd rect
			(at 0 4.800092 270)
			(size 2.3876 0.508)
			(layers "F.Cu" "F.Mask" "F.Paste")
			(net "P3V3_STBY")
		)
		(pad "14" smd rect
			(at 4.787646 4.800092 270)
			(size 2.3876 0.508)
			(layers "F.Cu" "F.Mask" "F.Paste")
			(net "GND")
		)
		(pad "15" smd rect
			(at 0 5.599938 270)
			(size 2.3876 0.508)
			(layers "F.Cu" "F.Mask" "F.Paste")
			(net "GND")
		)
		(pad "16" smd rect
			(at 4.787646 5.599938 270)
			(size 2.3876 0.508)
			(layers "F.Cu" "F.Mask" "F.Paste")
			(net "GND")
		)
		(pad "17" smd rect
			(at 0 6.400038 270)
			(size 2.3876 0.508)
			(layers "F.Cu" "F.Mask" "F.Paste")
			(net "GND")
		)
		(pad "18" smd rect
			(at 4.787646 6.400038 270)
			(size 2.3876 0.508)
			(layers "F.Cu" "F.Mask" "F.Paste")
			(net "P3V3")
		)
		(pad "19" smd rect
			(at 0 7.199884 270)
			(size 2.3876 0.508)
			(layers "F.Cu" "F.Mask" "F.Paste")
			(net "P3V3")
		)
		(pad "20" smd rect
			(at 4.787646 7.199884 270)
			(size 2.3876 0.508)
			(layers "F.Cu" "F.Mask" "F.Paste")
			(net "P3V3")
		)
		(pad "21" smd rect
			(at 0 7.999984 270)
			(size 2.3876 0.508)
			(layers "F.Cu" "F.Mask" "F.Paste")
			(net "P3V3")
		)
		(pad "22" smd rect
			(at 4.787646 7.999984 270)
			(size 2.3876 0.508)
			(layers "F.Cu" "F.Mask" "F.Paste")
			(net "P3V3")
		)
		(pad "23" smd rect
			(at 0 8.800084 270)
			(size 2.3876 0.508)
			(layers "F.Cu" "F.Mask" "F.Paste")
			(net "P3V3")
		)
		(pad "24" smd rect
			(at 4.787646 8.800084 270)
			(size 2.3876 0.508)
			(layers "F.Cu" "F.Mask" "F.Paste")
			(net "P3V3")
		)
		(pad "25" smd rect
			(at 0 9.59993 270)
			(size 2.3876 0.508)
			(layers "F.Cu" "F.Mask" "F.Paste")
			(net "P3V3")
		)
		(pad "26" smd rect
			(at 4.787646 9.59993 270)
			(size 2.3876 0.508)
			(layers "F.Cu" "F.Mask" "F.Paste")
			(net "GND")
		)
		(pad "27" smd rect
			(at 0 10.40003 270)
			(size 2.3876 0.508)
			(layers "F.Cu" "F.Mask" "F.Paste")
			(net "RMII_BMC_OCP_CRSDV_R")
		)
		(pad "28" smd rect
			(at 4.787646 10.40003 270)
			(size 2.3876 0.508)
			(layers "F.Cu" "F.Mask" "F.Paste")
			(net "IRQ_MEZZ_LAN_ALERT_N")
		)
		(pad "29" smd rect
			(at 0 11.199876 270)
			(size 2.3876 0.508)
			(layers "F.Cu" "F.Mask" "F.Paste")
			(net "CLK_50M_CKMNG_OCP")
		)
		(pad "30" smd rect
			(at 4.787646 11.199876 270)
			(size 2.3876 0.508)
			(layers "F.Cu" "F.Mask" "F.Paste")
			(net "SMB_OCP_FRU_STBY_LVC3_SCL")
		)
		(pad "31" smd rect
			(at 0 11.999976 270)
			(size 2.3876 0.508)
			(layers "F.Cu" "F.Mask" "F.Paste")
			(net "RMII_BMC_OCP_TXEN")
		)
		(pad "32" smd rect
			(at 4.787646 11.999976 270)
			(size 2.3876 0.508)
			(layers "F.Cu" "F.Mask" "F.Paste")
			(net "SMB_OCP_FRU_STBY_LVC3_SDA")
		)
		(pad "33" smd rect
			(at 0 12.800076 270)
			(size 2.3876 0.508)
			(layers "F.Cu" "F.Mask" "F.Paste")
			(net "RST_PCIE_CPU_DEV0_R_N")
		)
		(pad "34" smd rect
			(at 4.787646 12.800076 270)
			(size 2.3876 0.508)
			(layers "F.Cu" "F.Mask" "F.Paste")
			(net "FM_PE_OCP_WAKE_N")
		)
		(pad "35" smd rect
			(at 0 13.599922 270)
			(size 2.3876 0.508)
			(layers "F.Cu" "F.Mask" "F.Paste")
			(net "SMB_OCP_LAN_STBY_LVC3_SCL")
		)
		(pad "36" smd rect
			(at 4.787646 13.599922 270)
			(size 2.3876 0.508)
			(layers "F.Cu" "F.Mask" "F.Paste")
			(net "RMII_BMC_OCP_RXER_R")
		)
		(pad "37" smd rect
			(at 0 14.400022 270)
			(size 2.3876 0.508)
			(layers "F.Cu" "F.Mask" "F.Paste")
			(net "SMB_OCP_LAN_STBY_LVC3_SDA")
		)
		(pad "38" smd rect
			(at 4.787646 14.400022 270)
			(size 2.3876 0.508)
			(layers "F.Cu" "F.Mask" "F.Paste")
			(net "GND")
		)
		(pad "39" smd rect
			(at 0 15.200122 270)
			(size 2.3876 0.508)
			(layers "F.Cu" "F.Mask" "F.Paste")
			(net "GND")
		)
		(pad "40" smd rect
			(at 4.787646 15.200122 270)
			(size 2.3876 0.508)
			(layers "F.Cu" "F.Mask" "F.Paste")
			(net "RMII_BMC_OCP_TXD0")
		)
		(pad "41" smd rect
			(at 0 15.999968 270)
			(size 2.3876 0.508)
			(layers "F.Cu" "F.Mask" "F.Paste")
			(net "GND")
		)
		(pad "42" smd rect
			(at 4.787646 15.999968 270)
			(size 2.3876 0.508)
			(layers "F.Cu" "F.Mask" "F.Paste")
			(net "RMII_BMC_OCP_TXD1")
		)
		(pad "43" smd rect
			(at 0 16.800068 270)
			(size 2.3876 0.508)
			(layers "F.Cu" "F.Mask" "F.Paste")
			(net "RMII_BMC_OCP_RXD0_R")
		)
		(pad "44" smd rect
			(at 4.787646 16.800068 270)
			(size 2.3876 0.508)
			(layers "F.Cu" "F.Mask" "F.Paste")
			(net "GND")
		)
		(pad "45" smd rect
			(at 0 17.599914 270)
			(size 2.3876 0.508)
			(layers "F.Cu" "F.Mask" "F.Paste")
			(net "RMII_BMC_OCP_RXD1_R")
		)
		(pad "46" smd rect
			(at 4.787646 17.599914 270)
			(size 2.3876 0.508)
			(layers "F.Cu" "F.Mask" "F.Paste")
			(net "GND")
		)
		(pad "47" smd rect
			(at 0 18.400014 270)
			(size 2.3876 0.508)
			(layers "F.Cu" "F.Mask" "F.Paste")
			(net "GND")
		)
	)
)
